# SCM (Grand Teton) — schematic netlist excerpt (pin names and nets, part order shuffled) for the footprints in the layout excerpt that follows; sources: Cadence DE-HDL packaged netlist, KiCad conversion of 12092022_DA0F0TMDCD0_F0T_Management_Board_D_brd_V3_OCP.brd

R620  Q_RES  100K 1% CHIP  pkg 0402LF  page 48 : A = FM_JTAG_TCK_MUX_BMC_SEL ; B = GND
PR245  Q_RES  100K 1% EMPTY  pkg 0402LF  page 51 : A = PWRGD_P5V_AUX_R ; B = GND

(kicad_pcb
	(version 20260206)
	(generator "pcbnew")
	(generator_version "10.0")
	(general
		(thickness 1.6)
		(legacy_teardrops no)
	)
	(paper "A4")
	(title_block
		(title "12092022_DA0F0TMDCD0_F0T_Management_Board_D_brd_V3_OCP.brd")
		(comment 1 "Grand Teton / footprints 497-498 of 1440")
	)
	(layers
		(0 "F.Cu" signal "TOP")
		(4 "In1.Cu" signal "GND")
		(6 "In2.Cu" signal "IN1")
		(8 "In3.Cu" signal "GND1")
		(10 "In4.Cu" signal "IN2")
		(12 "In5.Cu" signal "VCC")
		(14 "In6.Cu" signal "VCC1")
		(16 "In7.Cu" signal "IN3")
		(18 "In8.Cu" signal "GND2")
		(20 "In9.Cu" signal "IN4")
		(22 "In10.Cu" signal "GND3")
		(2 "B.Cu" signal "BOTTOM")
		(9 "F.Adhes" user "F.Adhesive")
		(11 "B.Adhes" user "B.Adhesive")
		(13 "F.Paste" user "Package Geometry/Pastemask Top")
		(15 "B.Paste" user "Package Geometry/Pastemask Bottom")
		(5 "F.SilkS" user "Ref Des/Silkscreen Top")
		(7 "B.SilkS" user "Ref Des/Silkscreen Bottom")
		(1 "F.Mask" user "Board Geometry/Soldermask Top")
		(3 "B.Mask" user "Board Geometry/Soldermask Bottom")
		(17 "Dwgs.User" user "User.Drawings")
		(19 "Cmts.User" user "User.Comments")
		(21 "Eco1.User" user "User.Eco1")
		(23 "Eco2.User" user "User.Eco2")
		(25 "Edge.Cuts" user "Board Geometry/Outline")
		(27 "Margin" user)
		(31 "F.CrtYd" user "Package Geometry/Place Bound Top")
		(29 "B.CrtYd" user "Package Geometry/Place Bound Bottom")
		(35 "F.Fab" user "Ref Des/Assembly Top")
		(33 "B.Fab" user "Ref Des/Assembly Bottom")
	)
	(footprint ""
		(layer "F.Cu")
		(at 11.171936 -53.518054)
		(property "Reference" "PR245"
			(at 0 0 0)
			(layer "F.SilkS")
			(hide yes)
			(effects
				(font
					(size 1.27 1.27)
				)
			)
		)
		(property "Value" ""
			(at 0 0 0)
			(layer "F.Fab")
			(effects
				(font
					(size 1.27 1.27)
				)
			)
		)
		(duplicate_pad_numbers_are_jumpers no)
		(fp_line
			(start -0.7874 -0.4064)
			(end 0.7874 -0.4064)
			(stroke
				(width 0.1524)
				(type default)
			)
			(layer "F.SilkS")
		)
		(fp_line
			(start -0.7874 0.4064)
			(end -0.7874 -0.4064)
			(stroke
				(width 0.1524)
				(type default)
			)
			(layer "F.SilkS")
		)
		(fp_line
			(start 0.7874 -0.4064)
			(end 0.7874 0.4064)
			(stroke
				(width 0.1524)
				(type default)
			)
			(layer "F.SilkS")
		)
		(fp_line
			(start 0.7874 0.4064)
			(end -0.7874 0.4064)
			(stroke
				(width 0.1524)
				(type default)
			)
			(layer "F.SilkS")
		)
		(fp_line
			(start -0.67945 -0.305054)
			(end -0.12065 -0.305054)
			(stroke
				(width 0.1)
				(type default)
			)
			(layer "F.Fab")
		)
		(fp_line
			(start -0.67945 0.3048)
			(end -0.67945 -0.305054)
			(stroke
				(width 0.1)
				(type default)
			)
			(layer "F.Fab")
		)
		(fp_line
			(start -0.12065 -0.305054)
			(end -0.12065 -0.2794)
			(stroke
				(width 0.1)
				(type default)
			)
			(layer "F.Fab")
		)
		(fp_line
			(start -0.12065 -0.2794)
			(end 0.12065 -0.2794)
			(stroke
				(width 0.1)
				(type default)
			)
			(layer "F.Fab")
		)
		(fp_line
			(start -0.12065 0.2794)
			(end -0.12065 0.3048)
			(stroke
				(width 0.1)
				(type default)
			)
			(layer "F.Fab")
		)
		(fp_line
			(start -0.12065 0.3048)
			(end -0.67945 0.3048)
			(stroke
				(width 0.1)
				(type default)
			)
			(layer "F.Fab")
		)
		(fp_line
			(start 0.120396 0.2794)
			(end -0.12065 0.2794)
			(stroke
				(width 0.1)
				(type default)
			)
			(layer "F.Fab")
		)
		(fp_line
			(start 0.120396 0.3048)
			(end 0.120396 0.2794)
			(stroke
				(width 0.1)
				(type default)
			)
			(layer "F.Fab")
		)
		(fp_line
			(start 0.12065 -0.3048)
			(end 0.67945 -0.3048)
			(stroke
				(width 0.1)
				(type default)
			)
			(layer "F.Fab")
		)
		(fp_line
			(start 0.12065 -0.2794)
			(end 0.12065 -0.3048)
			(stroke
				(width 0.1)
				(type default)
			)
			(layer "F.Fab")
		)
		(fp_line
			(start 0.67945 -0.3048)
			(end 0.67945 0.3048)
			(stroke
				(width 0.1)
				(type default)
			)
			(layer "F.Fab")
		)
		(fp_line
			(start 0.67945 0.3048)
			(end 0.120396 0.3048)
			(stroke
				(width 0.1)
				(type default)
			)
			(layer "F.Fab")
		)
		(pad "1" smd circle
			(at -0.40005 0)
			(size 0 0)
			(layers "F.Cu" "F.Mask" "F.Paste")
			(net "PWRGD_P5V_AUX_R")
		)
		(pad "2" smd circle
			(at 0.40005 0)
			(size 0 0)
			(layers "F.Cu" "F.Mask" "F.Paste")
			(net "GND")
		)
	)
	(footprint ""
		(layer "F.Cu")
		(at 76.981558 -74.476356 90)
		(property "Reference" "R620"
			(at 0 0 90)
			(layer "F.SilkS")
			(hide yes)
			(effects
				(font
					(size 1.27 1.27)
				)
			)
		)
		(property "Value" ""
			(at 0 0 90)
			(layer "F.Fab")
			(effects
				(font
					(size 1.27 1.27)
				)
			)
		)
		(duplicate_pad_numbers_are_jumpers no)
		(fp_line
			(start 0.7874 -0.4064)
			(end 0.7874 0.4064)
			(stroke
				(width 0.1524)
				(type default)
			)
			(layer "F.SilkS")
		)
		(fp_line
			(start -0.7874 -0.4064)
			(end 0.7874 -0.4064)
			(stroke
				(width 0.1524)
				(type default)
			)
			(layer "F.SilkS")
		)
		(fp_line
			(start 0.7874 0.4064)
			(end -0.7874 0.4064)
			(stroke
				(width 0.1524)
				(type default)
			)
			(layer "F.SilkS")
		)
		(fp_line
			(start -0.7874 0.4064)
			(end -0.7874 -0.4064)
			(stroke
				(width 0.1524)
				(type default)
			)
			(layer "F.SilkS")
		)
		(fp_line
			(start -0.12065 -0.305054)
			(end -0.12065 -0.2794)
			(stroke
				(width 0.1)
				(type default)
			)
			(layer "F.Fab")
		)
		(fp_line
			(start -0.67945 -0.305054)
			(end -0.12065 -0.305054)
			(stroke
				(width 0.1)
				(type default)
			)
			(layer "F.Fab")
		)
		(fp_line
			(start 0.67945 -0.3048)
			(end 0.67945 0.3048)
			(stroke
				(width 0.1)
				(type default)
			)
			(layer "F.Fab")
		)
		(fp_line
			(start 0.12065 -0.3048)
			(end 0.67945 -0.3048)
			(stroke
				(width 0.1)
				(type default)
			)
			(layer "F.Fab")
		)
		(fp_line
			(start 0.12065 -0.2794)
			(end 0.12065 -0.3048)
			(stroke
				(width 0.1)
				(type default)
			)
			(layer "F.Fab")
		)
		(fp_line
			(start -0.12065 -0.2794)
			(end 0.12065 -0.2794)
			(stroke
				(width 0.1)
				(type default)
			)
			(layer "F.Fab")
		)
		(fp_line
			(start 0.120396 0.2794)
			(end -0.12065 0.2794)
			(stroke
				(width 0.1)
				(type default)
			)
			(layer "F.Fab")
		)
		(fp_line
			(start -0.12065 0.2794)
			(end -0.12065 0.3048)
			(stroke
				(width 0.1)
				(type default)
			)
			(layer "F.Fab")
		)
		(fp_line
			(start 0.67945 0.3048)
			(end 0.120396 0.3048)
			(stroke
				(width 0.1)
				(type default)
			)
			(layer "F.Fab")
		)
		(fp_line
			(start 0.120396 0.3048)
			(end 0.120396 0.2794)
			(stroke
				(width 0.1)
				(type default)
			)
			(layer "F.Fab")
		)
		(fp_line
			(start -0.12065 0.3048)
			(end -0.67945 0.3048)
			(stroke
				(width 0.1)
				(type default)
			)
			(layer "F.Fab")
		)
		(fp_line
			(start -0.67945 0.3048)
			(end -0.67945 -0.305054)
			(stroke
				(width 0.1)
				(type default)
			)
			(layer "F.Fab")
		)
		(pad "1" smd circle
			(at -0.40005 0 90)
			(size 0 0)
			(layers "F.Cu" "F.Mask" "F.Paste")
			(net "FM_JTAG_TCK_MUX_BMC_SEL")
		)
		(pad "2" smd circle
			(at 0.40005 0 90)
			(size 0 0)
			(layers "F.Cu" "F.Mask" "F.Paste")
			(net "GND")
		)
	)
)
